FILE_TYPE = CONNECTIVITY;
{Allegro Design Entry HDL 17.2-2016 S081 (4005846) 1/11/2022}
"PAGE_NUMBER" = 123;
0"NC";
1"PVNN_TERM_CPU1\g";
2"PVNN_TERM_CPU1\g";
3"PVNN_TERM_CPU0\g";
4"PVNN_TERM_CPU0\g";
5"PVNN_TERM_CPU1\g";
6"PVNN_TERM_CPU0\g";
7"P3V3\g";
8"P3V3\g";
9"GND\g";
10"GND\g";
11"H_CPU0_MEMTRIP_LVC1_N";
12"H_CPU1_MEMTRIP_LVC1_N";
13"H_CPU0_NMI_LVC1_N";
14"H_CPU1_NMI_LVC1_N";
15"H_CPU0_MEMTRIP_VT_N";
16"H_CPU1_MEMTRIP_VT_N";
17"H_CPU1_MEMTRIP_R";
18"H_CPU0_MEMTRIP_R";
19"H_CPU0_MEMTRIP";
20"H_CPU1_MEMTRIP";
21"H_CPU0_MEMTRIP_OUT_VT_R_N";
22"H_CPU1_MEMTRIP_OUT_VT_R_N";
23"H_CPU_NMI_LVC1_N";
24"H_CPU_NMI_LVC1_R_N";
25"H_CPU1_MEMTRIP_LVC1_R_N";
26"H_CPU0_MEMTRIP_LVC1_R_N";
%"Q_RES"
"1","(-3025,-775)","0","pure_quanta","I10";
;
PART_NUMBER"CS21502FB07"
MATERIAL"CHIP"
PACK_TYPE"0402LF"
VALUE"1.5K"
TOLERANCE"1%"
WATTAGE"1/16W"
LOCATION"R205"
CDS_LIB"pure_quanta"
$SEC"1"
CDS_SEC"1";
"B"
$PN"2"21;
"A"
$PN"1"26;
%"BC847BPN"
"2","(-2025,-2125)","0","pure_quanta","I11";
;
PART_NUMBER"BA008470026"
MATERIAL"IC"
PART_TYPE"SMLF"
VALUE"BC847BPN"
LOCATION"Q140"
CDS_LIB"pure_quanta"
NEEDS_NO_SIZE"TRUE"
CDS_LMAN_SYM_OUTLINE"-50,50,50,-50"
$SEC"2"
CDS_SEC"2";
"E2"
$PN"4"2;
"C2"
$PN"3"20;
"B2"
$PN"5"22;
%"BC847BPN"
"2","(-2025,-775)","0","pure_quanta","I12";
;
PART_NUMBER"BA008470026"
PART_TYPE"SMLF"
MATERIAL"IC"
VALUE"BC847BPN"
LOCATION"Q141"
CDS_LIB"pure_quanta"
NEEDS_NO_SIZE"TRUE"
CDS_LMAN_SYM_OUTLINE"-50,50,50,-50"
$SEC"2"
CDS_SEC"2";
"E2"
$PN"4"4;
"C2"
$PN"3"19;
"B2"
$PN"5"21;
%"UNIVERSAL_POWER"
"1","(-1975,-1875)","0","logical_power","I13";
;
HDL_POWER"PVNN_TERM_CPU1"
CDS_LIB"logical_power";
"A"2;
%"Q_RES"
"1","(-1250,-2375)","0","pure_quanta","I14";
;
PART_NUMBER"CS21502FB07"
MATERIAL"CHIP"
PACK_TYPE"0402LF"
VALUE"1.5K"
$LOCATION"R4410"
CDS_LIB"pure_quanta"
TOLERANCE"1%"
WATTAGE"1/16W"
CDS_LOCATION"R4410"
$SEC"1"
CDS_SEC"1";
"B"
$PN"2"17;
"A"
$PN"1"20;
%"Q_RES"
"1","(-1250,-1025)","0","pure_quanta","I15";
;
PART_NUMBER"CS21502FB07"
PACK_TYPE"0402LF"
VALUE"1.5K"
MATERIAL"CHIP"
$LOCATION"R4409"
CDS_LIB"pure_quanta"
TOLERANCE"1%"
WATTAGE"1/16W"
CDS_LOCATION"R4409"
$SEC"1"
CDS_SEC"1";
"B"
$PN"2"18;
"A"
$PN"1"19;
%"BC847BPN"
"1","(-475,-2375)","0","pure_quanta","I16";
;
PART_NUMBER"BA008470026"
PART_TYPE"SMLF"
MATERIAL"IC"
VALUE"BC847BPN"
LOCATION"Q140"
CDS_LIB"pure_quanta"
NEEDS_NO_SIZE"TRUE"
CDS_LMAN_SYM_OUTLINE"-50,50,50,-50"
$SEC"1"
CDS_SEC"1";
"E1"
$PN"1"9;
"C1"
$PN"6"16;
"B1"
$PN"2"17;
%"UNIVERSAL_GND"
"1","(-375,-2050)","0","logical_power","I17";
;
CDS_LIB"logical_power"
HDL_POWER"GND";
"A"9;
%"BC847BPN"
"1","(-475,-1025)","0","pure_quanta","I18";
;
PART_NUMBER"BA008470026"
PART_TYPE"SMLF"
MATERIAL"IC"
VALUE"BC847BPN"
LOCATION"Q141"
CDS_LIB"pure_quanta"
NEEDS_NO_SIZE"TRUE"
CDS_LMAN_SYM_OUTLINE"-50,50,50,-50"
$SEC"1"
CDS_SEC"1";
"E1"
$PN"1"10;
"C1"
$PN"6"15;
"B1"
$PN"2"18;
%"Q_RES"
"2","(-3375,-500)","0","pure_quanta","I19";
;
PART_NUMBER"CS11002FB07"
VALUE"100"
TOLERANCE"1%"
MATERIAL"CHIP"
WATTAGE"1/16W"
PACK_TYPE"0402LF"
LOCATION"R200"
CDS_LIB"pure_quanta"
$SEC"1"
CDS_SEC"1";
"A"
$PN"1"3;
"B"
$PN"2"26;
%"UNIVERSAL_POWER"
"1","(-3375,-300)","0","logical_power","I20";
;
HDL_POWER"PVNN_TERM_CPU0"
CDS_LIB"logical_power";
"A"3;
%"UNIVERSAL_POWER"
"1","(-1975,-525)","0","logical_power","I21";
;
HDL_POWER"PVNN_TERM_CPU0"
CDS_LIB"logical_power";
"A"4;
%"UNIVERSAL_GND"
"1","(-375,-700)","0","logical_power","I22";
;
CDS_LIB"logical_power"
HDL_POWER"GND";
"A"10;
%"Q_RES"
"2","(1025,-5350)","0","pure_quanta","I23";
;
PART_NUMBER"CS13012FB02"
WATTAGE"1/16W"
MATERIAL"CHIP"
PACK_TYPE"0402LF"
VALUE"301"
TOLERANCE"1%"
LOCATION"R198"
CDS_LIB"pure_quanta"
$SEC"1"
CDS_SEC"1";
"A"
$PN"1"5;
"B"
$PN"2"14;
%"UNIVERSAL_POWER"
"1","(1025,-5100)","0","logical_power","I24";
;
HDL_POWER"PVNN_TERM_CPU1"
CDS_LIB"logical_power";
"A"5;
%"Q_RES"
"2","(1025,-4675)","0","pure_quanta","I27";
;
PART_NUMBER"CS13012FB02"
PACK_TYPE"0402LF"
VALUE"301"
WATTAGE"1/16W"
MATERIAL"CHIP"
TOLERANCE"1%"
LOCATION"R197"
CDS_LIB"pure_quanta"
$SEC"1"
CDS_SEC"1";
"A"
$PN"1"6;
"B"
$PN"2"13;
%"UNIVERSAL_POWER"
"1","(1025,-4375)","0","logical_power","I28";
;
HDL_POWER"PVNN_TERM_CPU0"
CDS_LIB"logical_power";
"A"6;
%"Q_RES"
"2","(375,-2225)","0","pure_quanta","I29";
;
PART_NUMBER"CS24752FB03"
WATTAGE"1/16W"
TOLERANCE"1%"
VALUE"4.75K"
MATERIAL"CHIP"
PACK_TYPE"0402LF"
$LOCATION"R4412"
CDS_LIB"pure_quanta"
CDS_LOCATION"R4412"
$SEC"1"
CDS_SEC"1";
"A"
$PN"1"7;
"B"
$PN"2"16;
%"UNIVERSAL_POWER"
"1","(375,-1975)","0","logical_power","I30";
;
HDL_POWER"P3V3"
CDS_LIB"logical_power";
"A"7;
%"Q_RES"
"1","(1025,-2600)","0","pure_quanta","I31";
;
PART_NUMBER"CS03322FB03"
MATERIAL"CHIP"
PACK_TYPE"0402LF"
WATTAGE"1/16W"
VALUE"33.2"
TOLERANCE"1%"
$LOCATION"R4414"
CDS_LIB"pure_quanta"
CDS_LOCATION"R4414"
$SEC"1"
CDS_SEC"1";
"B"
$PN"2"12;
"A"
$PN"1"16;
%"Q_RES"
"2","(375,-875)","0","pure_quanta","I32";
;
PART_NUMBER"CS24752FB03"
MATERIAL"CHIP"
VALUE"4.75K"
WATTAGE"1/16W"
TOLERANCE"1%"
PACK_TYPE"0402LF"
$LOCATION"R4411"
CDS_LIB"pure_quanta"
CDS_LOCATION"R4411"
$SEC"1"
CDS_SEC"1";
"A"
$PN"1"8;
"B"
$PN"2"15;
%"Q_RES"
"1","(1025,-1250)","0","pure_quanta","I33";
;
PART_NUMBER"CS03322FB03"
TOLERANCE"1%"
VALUE"33.2"
WATTAGE"1/16W"
MATERIAL"CHIP"
PACK_TYPE"0402LF"
$LOCATION"R4413"
CDS_LIB"pure_quanta"
CDS_LOCATION"R4413"
$SEC"1"
CDS_SEC"1";
"B"
$PN"2"11;
"A"
$PN"1"15;
%"UNIVERSAL_POWER"
"1","(375,-625)","0","logical_power","I36";
;
HDL_POWER"P3V3"
CDS_LIB"logical_power";
"A"8;
%"Q_RES"
"1","(-1875,-4925)","0","pure_quanta","I4";
;
PART_NUMBER"CS00002JB13"
TOLERANCE"5%"
VALUE"0"
WATTAGE"1/16W"
MATERIAL"CHIP"
PACK_TYPE"0402LF"
$LOCATION"R188"
CDS_LIB"pure_quanta"
CDS_LOCATION"R188"
$SEC"1"
CDS_SEC"1";
"B"
$PN"2"23;
"A"
$PN"1"24;
%"Q_RES"
"1","(-25,-5600)","0","pure_quanta","I5";
;
PART_NUMBER"CS04992FB07"
MATERIAL"CHIP"
TOLERANCE"1%"
WATTAGE"1/16W"
VALUE"49.9"
PACK_TYPE"0402LF"
$LOCATION"R196"
CDS_LIB"pure_quanta"
CDS_LOCATION"R196"
$SEC"1"
CDS_SEC"1";
"B"
$PN"2"14;
"A"
$PN"1"23;
%"Q_RES"
"1","(-25,-4925)","0","pure_quanta","I6";
;
PART_NUMBER"CS04992FB07"
TOLERANCE"1%"
VALUE"49.9"
WATTAGE"1/16W"
PACK_TYPE"0402LF"
MATERIAL"CHIP"
$LOCATION"R195"
CDS_LIB"pure_quanta"
CDS_LOCATION"R195"
$SEC"1"
CDS_SEC"1";
"B"
$PN"2"13;
"A"
$PN"1"23;
%"Q_RES"
"2","(-3375,-1850)","0","pure_quanta","I7";
;
PART_NUMBER"CS11002FB07"
PACK_TYPE"0402LF"
VALUE"100"
MATERIAL"CHIP"
TOLERANCE"1%"
WATTAGE"1/16W"
LOCATION"R202"
CDS_LIB"pure_quanta"
$SEC"1"
CDS_SEC"1";
"A"
$PN"1"1;
"B"
$PN"2"25;
%"Q_RES"
"1","(-3025,-2125)","0","pure_quanta","I8";
;
PART_NUMBER"CS21502FB07"
WATTAGE"1/16W"
VALUE"1.5K"
TOLERANCE"1%"
PACK_TYPE"0402LF"
MATERIAL"CHIP"
LOCATION"R206"
CDS_LIB"pure_quanta"
$SEC"1"
CDS_SEC"1";
"B"
$PN"2"22;
"A"
$PN"1"25;
%"UNIVERSAL_POWER"
"1","(-3375,-1650)","0","logical_power","I9";
;
HDL_POWER"PVNN_TERM_CPU1"
CDS_LIB"logical_power";
"A"1;
END.
